FILE_TYPE = CONNECTIVITY;
{Allegro Design Entry HDL 17.2-2016 S081 (4005846) 1/11/2022}
"PAGE_NUMBER" = 125;
0"NC";
END.
